# S9S_MB_2U (Grand Teton) — schematic netlist excerpt (pin names and nets, part order shuffled) for the footprints in the layout excerpt that follows; sources: Cadence DE-HDL packaged netlist, KiCad conversion of 03242023_DA0F0TMBIJ0_F0T_Motherboard_J_brd_V01_OCP.brd

R2568  Q_RES  1K 1% CHIP  pkg 0402LF  page 292 : A = P3V3_AUX ; B = PVCCINFAON_CPU1_VR_FAULT
C873  Q_CAP_DIFFBUS  DIFF BUS_0.22UF 6.3V 20% X6S  pkg C0201  page 174 : \1\ = P5E_CPU0_PE3_TX_C_DP<14> ; \2\ = P5E_CPU0_PE3_TX_DP<14>
R3035  Q_RES  4.7K 5% CHIP  pkg 0402LF  page 148 : A = P3V3_AUX ; B = FM_SMB_2_ALERT_GPU_ISO_N

(kicad_pcb
	(version 20260206)
	(generator "pcbnew")
	(generator_version "10.0")
	(general
		(thickness 1.6)
		(legacy_teardrops no)
	)
	(paper "A4")
	(title_block
		(title "03242023_DA0F0TMBIJ0_F0T_Motherboard_J_brd_V01_OCP.brd")
		(comment 1 "Grand Teton / footprints 1270-1272 of 6105")
	)
	(layers
		(0 "F.Cu" signal "TOP")
		(4 "In1.Cu" signal "GND")
		(6 "In2.Cu" signal "IN1")
		(8 "In3.Cu" signal "GND1")
		(10 "In4.Cu" signal "IN2")
		(12 "In5.Cu" signal "GND2")
		(14 "In6.Cu" signal "IN3")
		(16 "In7.Cu" signal "GND3")
		(18 "In8.Cu" signal "VCC")
		(20 "In9.Cu" signal "VCC1")
		(22 "In10.Cu" signal "GND4")
		(24 "In11.Cu" signal "IN4")
		(26 "In12.Cu" signal "GND5")
		(28 "In13.Cu" signal "IN5")
		(30 "In14.Cu" signal "GND6")
		(32 "In15.Cu" signal "IN6")
		(34 "In16.Cu" signal "GND7")
		(2 "B.Cu" signal "BOTTOM")
		(9 "F.Adhes" user "F.Adhesive")
		(11 "B.Adhes" user "B.Adhesive")
		(13 "F.Paste" user "Package Geometry/Pastemask Top")
		(15 "B.Paste" user "Package Geometry/Pastemask Bottom")
		(5 "F.SilkS" user "Ref Des/Silkscreen Top")
		(7 "B.SilkS" user "Ref Des/Silkscreen Bottom")
		(1 "F.Mask" user "Board Geometry/Soldermask Top")
		(3 "B.Mask" user "Board Geometry/Soldermask Bottom")
		(17 "Dwgs.User" user "User.Drawings")
		(19 "Cmts.User" user "User.Comments")
		(21 "Eco1.User" user "User.Eco1")
		(23 "Eco2.User" user "User.Eco2")
		(25 "Edge.Cuts" user "Board Geometry/Outline")
		(27 "Margin" user)
		(31 "F.CrtYd" user "Package Geometry/Place Bound Top")
		(29 "B.CrtYd" user "Package Geometry/Place Bound Bottom")
		(35 "F.Fab" user "Ref Des/Assembly Top")
		(33 "B.Fab" user "Ref Des/Assembly Bottom")
	)
	(footprint ""
		(layer "F.Cu")
		(at 27.0383 -131.55295)
		(property "Reference" "R2568"
			(at 0 0 0)
			(layer "F.SilkS")
			(hide yes)
			(effects
				(font
					(size 1.27 1.27)
				)
			)
		)
		(property "Value" ""
			(at 0 0 0)
			(layer "F.Fab")
			(effects
				(font
					(size 1.27 1.27)
				)
			)
		)
		(duplicate_pad_numbers_are_jumpers no)
		(fp_line
			(start -0.7874 -0.4064)
			(end 0.7874 -0.4064)
			(stroke
				(width 0.1524)
				(type default)
			)
			(layer "F.SilkS")
		)
		(fp_line
			(start -0.7874 0.4064)
			(end -0.7874 -0.4064)
			(stroke
				(width 0.1524)
				(type default)
			)
			(layer "F.SilkS")
		)
		(fp_line
			(start 0.7874 -0.4064)
			(end 0.7874 0.4064)
			(stroke
				(width 0.1524)
				(type default)
			)
			(layer "F.SilkS")
		)
		(fp_line
			(start 0.7874 0.4064)
			(end -0.7874 0.4064)
			(stroke
				(width 0.1524)
				(type default)
			)
			(layer "F.SilkS")
		)
		(fp_line
			(start -0.67945 -0.305054)
			(end -0.12065 -0.305054)
			(stroke
				(width 0.1)
				(type default)
			)
			(layer "F.Fab")
		)
		(fp_line
			(start -0.67945 0.3048)
			(end -0.67945 -0.305054)
			(stroke
				(width 0.1)
				(type default)
			)
			(layer "F.Fab")
		)
		(fp_line
			(start -0.12065 -0.305054)
			(end -0.12065 -0.2794)
			(stroke
				(width 0.1)
				(type default)
			)
			(layer "F.Fab")
		)
		(fp_line
			(start -0.12065 -0.2794)
			(end 0.12065 -0.2794)
			(stroke
				(width 0.1)
				(type default)
			)
			(layer "F.Fab")
		)
		(fp_line
			(start -0.12065 0.2794)
			(end -0.12065 0.3048)
			(stroke
				(width 0.1)
				(type default)
			)
			(layer "F.Fab")
		)
		(fp_line
			(start -0.12065 0.3048)
			(end -0.67945 0.3048)
			(stroke
				(width 0.1)
				(type default)
			)
			(layer "F.Fab")
		)
		(fp_line
			(start 0.120396 0.2794)
			(end -0.12065 0.2794)
			(stroke
				(width 0.1)
				(type default)
			)
			(layer "F.Fab")
		)
		(fp_line
			(start 0.120396 0.3048)
			(end 0.120396 0.2794)
			(stroke
				(width 0.1)
				(type default)
			)
			(layer "F.Fab")
		)
		(fp_line
			(start 0.12065 -0.3048)
			(end 0.67945 -0.3048)
			(stroke
				(width 0.1)
				(type default)
			)
			(layer "F.Fab")
		)
		(fp_line
			(start 0.12065 -0.2794)
			(end 0.12065 -0.3048)
			(stroke
				(width 0.1)
				(type default)
			)
			(layer "F.Fab")
		)
		(fp_line
			(start 0.67945 -0.3048)
			(end 0.67945 0.3048)
			(stroke
				(width 0.1)
				(type default)
			)
			(layer "F.Fab")
		)
		(fp_line
			(start 0.67945 0.3048)
			(end 0.120396 0.3048)
			(stroke
				(width 0.1)
				(type default)
			)
			(layer "F.Fab")
		)
		(pad "1" smd circle
			(at -0.40005 0)
			(size 0 0)
			(layers "F.Cu" "F.Mask" "F.Paste")
			(net "P3V3_AUX")
		)
		(pad "2" smd circle
			(at 0.40005 0)
			(size 0 0)
			(layers "F.Cu" "F.Mask" "F.Paste")
			(net "PVCCINFAON_CPU1_VR_FAULT")
		)
	)
	(footprint ""
		(layer "F.Cu")
		(at 112.27308 -397.874998 -90)
		(property "Reference" "R3035"
			(at 0 0 270)
			(layer "F.SilkS")
			(hide yes)
			(effects
				(font
					(size 1.27 1.27)
				)
			)
		)
		(property "Value" ""
			(at 0 0 270)
			(layer "F.Fab")
			(effects
				(font
					(size 1.27 1.27)
				)
			)
		)
		(duplicate_pad_numbers_are_jumpers no)
		(fp_line
			(start -0.7874 0.4064)
			(end -0.7874 -0.4064)
			(stroke
				(width 0.1524)
				(type default)
			)
			(layer "F.SilkS")
		)
		(fp_line
			(start 0.7874 0.4064)
			(end -0.7874 0.4064)
			(stroke
				(width 0.1524)
				(type default)
			)
			(layer "F.SilkS")
		)
		(fp_line
			(start -0.7874 -0.4064)
			(end 0.7874 -0.4064)
			(stroke
				(width 0.1524)
				(type default)
			)
			(layer "F.SilkS")
		)
		(fp_line
			(start 0.7874 -0.4064)
			(end 0.7874 0.4064)
			(stroke
				(width 0.1524)
				(type default)
			)
			(layer "F.SilkS")
		)
		(fp_line
			(start -0.67945 0.3048)
			(end -0.67945 -0.305054)
			(stroke
				(width 0.1)
				(type default)
			)
			(layer "F.Fab")
		)
		(fp_line
			(start -0.12065 0.3048)
			(end -0.67945 0.3048)
			(stroke
				(width 0.1)
				(type default)
			)
			(layer "F.Fab")
		)
		(fp_line
			(start 0.120396 0.3048)
			(end 0.120396 0.2794)
			(stroke
				(width 0.1)
				(type default)
			)
			(layer "F.Fab")
		)
		(fp_line
			(start 0.67945 0.3048)
			(end 0.120396 0.3048)
			(stroke
				(width 0.1)
				(type default)
			)
			(layer "F.Fab")
		)
		(fp_line
			(start -0.12065 0.2794)
			(end -0.12065 0.3048)
			(stroke
				(width 0.1)
				(type default)
			)
			(layer "F.Fab")
		)
		(fp_line
			(start 0.120396 0.2794)
			(end -0.12065 0.2794)
			(stroke
				(width 0.1)
				(type default)
			)
			(layer "F.Fab")
		)
		(fp_line
			(start -0.12065 -0.2794)
			(end 0.12065 -0.2794)
			(stroke
				(width 0.1)
				(type default)
			)
			(layer "F.Fab")
		)
		(fp_line
			(start 0.12065 -0.2794)
			(end 0.12065 -0.3048)
			(stroke
				(width 0.1)
				(type default)
			)
			(layer "F.Fab")
		)
		(fp_line
			(start 0.12065 -0.3048)
			(end 0.67945 -0.3048)
			(stroke
				(width 0.1)
				(type default)
			)
			(layer "F.Fab")
		)
		(fp_line
			(start 0.67945 -0.3048)
			(end 0.67945 0.3048)
			(stroke
				(width 0.1)
				(type default)
			)
			(layer "F.Fab")
		)
		(fp_line
			(start -0.67945 -0.305054)
			(end -0.12065 -0.305054)
			(stroke
				(width 0.1)
				(type default)
			)
			(layer "F.Fab")
		)
		(fp_line
			(start -0.12065 -0.305054)
			(end -0.12065 -0.2794)
			(stroke
				(width 0.1)
				(type default)
			)
			(layer "F.Fab")
		)
		(pad "1" smd circle
			(at -0.40005 0 270)
			(size 0 0)
			(layers "F.Cu" "F.Mask" "F.Paste")
			(net "P3V3_AUX")
		)
		(pad "2" smd circle
			(at 0.40005 0 270)
			(size 0 0)
			(layers "F.Cu" "F.Mask" "F.Paste")
			(net "FM_SMB_2_ALERT_GPU_ISO_N")
		)
	)
	(footprint ""
		(layer "F.Cu")
		(at 376.72137 -408.517344 -90)
		(property "Reference" "C873"
			(at 0 0 270)
			(layer "F.SilkS")
			(hide yes)
			(effects
				(font
					(size 1.27 1.27)
				)
			)
		)
		(property "Value" ""
			(at 0 0 270)
			(layer "F.Fab")
			(effects
				(font
					(size 1.27 1.27)
				)
			)
		)
		(duplicate_pad_numbers_are_jumpers no)
		(fp_line
			(start -0.299974 0.150114)
			(end -0.299974 -0.150114)
			(stroke
				(width 0.1)
				(type default)
			)
			(layer "F.Fab")
		)
		(fp_line
			(start 0.299974 0.150114)
			(end -0.299974 0.150114)
			(stroke
				(width 0.1)
				(type default)
			)
			(layer "F.Fab")
		)
		(fp_line
			(start -0.299974 -0.150114)
			(end 0.299974 -0.150114)
			(stroke
				(width 0.1)
				(type default)
			)
			(layer "F.Fab")
		)
		(fp_line
			(start 0.299974 -0.150114)
			(end 0.299974 0.150114)
			(stroke
				(width 0.1)
				(type default)
			)
			(layer "F.Fab")
		)
		(pad "1" smd rect
			(at -0.2667 0 270)
			(size 0.3048 0.381)
			(layers "F.Cu" "F.Mask" "F.Paste")
			(net "P5E_CPU0_PE3_TX_C_DP<14>")
		)
		(pad "2" smd rect
			(at 0.2667 0 270)
			(size 0.3048 0.381)
			(layers "F.Cu" "F.Mask" "F.Paste")
			(net "P5E_CPU0_PE3_TX_DP<14>")
		)
	)
)
